(kicad_pcb
	(version 20260206)
	(generator "pcbnew")
	(generator_version "10.0")
	(general
		(thickness 1.21888)
		(legacy_teardrops no)
	)
	(paper "A4")
	(title_block
		(title "timecard-beta-v1 — TimeCard-DC-V1.PcbDoc")
		(comment 1 "Time Appliance Project (Time Card) / footprints 23-33 of 120")
	)
	(layers
		(0 "F.Cu" signal "TOP")
		(4 "In1.Cu" signal "SGND")
		(6 "In2.Cu" signal "IN1")
		(8 "In3.Cu" signal "IN2")
		(10 "In4.Cu" signal "SGND1")
		(2 "B.Cu" signal "BOTTOM")
		(9 "F.Adhes" user "F.Adhesive")
		(11 "B.Adhes" user "B.Adhesive")
		(13 "F.Paste" user "Top Paste")
		(15 "B.Paste" user "Bottom Paste")
		(5 "F.SilkS" user "Top Overlay")
		(7 "B.SilkS" user "Bottom Overlay")
		(1 "F.Mask" user "Top Solder")
		(3 "B.Mask" user "Bottom Solder")
		(17 "Dwgs.User" user "User.Drawings")
		(19 "Cmts.User" user "User.Comments")
		(21 "Eco1.User" user "User.Eco1")
		(23 "Eco2.User" user "User.Eco2")
		(25 "Edge.Cuts" user)
		(27 "Margin" user)
		(31 "F.CrtYd" user "Top Courtyard")
		(29 "B.CrtYd" user "Bottom Courtyard")
		(35 "F.Fab" user "Top Component Center")
		(33 "B.Fab" user "Bottom Component Center")
	)
	(footprint "Vault:CAPC1608X87X45ML20T05"
		(layer "F.Cu")
		(at 151.488595 86.2786 -90)
		(property "Reference" "C31"
			(at 2.721395 -0.026921 90)
			(unlocked yes)
			(layer "F.SilkS")
			(effects
				(font
					(size 0.762 0.762)
					(thickness 0.2286)
				)
			)
		)
		(property "Value" "0.1uF"
			(at 2.09443 2.657602 270)
			(unlocked yes)
			(layer "F.SilkS")
			(hide yes)
			(effects
				(font
					(size 1.524 1.524)
					(thickness 0.254)
				)
			)
		)
		(sheetname "GPS_IMU_SENSORS")
		(sheetfile "GPS_IMU_SENSORS.kicad_sch")
		(duplicate_pad_numbers_are_jumpers no)
		(pad "1" smd rect
			(at -0.7 0)
			(size 1.1 1.05)
			(layers "F.Cu" "F.Mask" "F.Paste")
			(net "GND")
		)
		(pad "2" smd rect
			(at 0.7 0)
			(size 1.1 1.05)
			(layers "F.Cu" "F.Mask" "F.Paste")
			(net "+3.3V")
		)
	)
	(footprint "Vault:FP-318BQ-MFG"
		(layer "F.Cu")
		(at 86.238595 122.8286)
		(property "Reference" "U8"
			(at 1.478605 2.776921 360)
			(unlocked yes)
			(layer "F.SilkS")
			(effects
				(font
					(size 0.762 0.762)
					(thickness 0.2286)
				)
			)
		)
		(property "Value" "NC7SZ125M5"
			(at 5.03956 3.495802 0)
			(unlocked yes)
			(layer "F.SilkS")
			(hide yes)
			(effects
				(font
					(size 1.524 1.524)
					(thickness 0.254)
				)
			)
		)
		(sheetname "USER_IO")
		(sheetfile "USER_IO.kicad_sch")
		(duplicate_pad_numbers_are_jumpers no)
		(fp_line
			(start -0.325 -1.575)
			(end 0.325 -1.575)
			(stroke
				(width 0.2)
				(type solid)
			)
			(layer "F.SilkS")
		)
		(fp_line
			(start -0.325 1.575)
			(end 0.325 1.575)
			(stroke
				(width 0.2)
				(type solid)
			)
			(layer "F.SilkS")
		)
		(fp_line
			(start 0.825 0.225)
			(end 0.825 -0.225)
			(stroke
				(width 0.2)
				(type solid)
			)
			(layer "F.SilkS")
		)
		(fp_circle
			(center -2.45 -0.95)
			(end -2.45 -1.075)
			(stroke
				(width 0.25)
				(type solid)
			)
			(fill no)
			(layer "F.SilkS")
		)
		(fp_line
			(start -1.8 -1.825)
			(end 1.8 -1.825)
			(stroke
				(width 0.2)
				(type solid)
			)
			(layer "F.CrtYd")
		)
		(fp_line
			(start -1.8 1.825)
			(end -1.8 -1.825)
			(stroke
				(width 0.2)
				(type solid)
			)
			(layer "F.CrtYd")
		)
		(fp_line
			(start -1.8 1.825)
			(end 1.8 1.825)
			(stroke
				(width 0.2)
				(type solid)
			)
			(layer "F.CrtYd")
		)
		(fp_line
			(start 1.8 1.825)
			(end 1.8 -1.825)
			(stroke
				(width 0.2)
				(type solid)
			)
			(layer "F.CrtYd")
		)
		(fp_line
			(start -1.8 -1.825)
			(end 1.8 -1.825)
			(stroke
				(width 0.2)
				(type solid)
			)
			(layer "F.Fab")
		)
		(fp_line
			(start -1.8 1.825)
			(end -1.8 -1.825)
			(stroke
				(width 0.2)
				(type solid)
			)
			(layer "F.Fab")
		)
		(fp_line
			(start -1.8 1.825)
			(end 1.8 1.825)
			(stroke
				(width 0.2)
				(type solid)
			)
			(layer "F.Fab")
		)
		(fp_line
			(start -0.5 0)
			(end 0.5 0)
			(stroke
				(width 0.1)
				(type solid)
			)
			(layer "F.Fab")
		)
		(fp_line
			(start 0 0.5)
			(end 0 -0.5)
			(stroke
				(width 0.1)
				(type solid)
			)
			(layer "F.Fab")
		)
		(fp_line
			(start 1.8 1.825)
			(end 1.8 -1.825)
			(stroke
				(width 0.2)
				(type solid)
			)
			(layer "F.Fab")
		)
		(fp_text user "${REFERENCE}"
			(at 0 0.28494 360)
			(unlocked yes)
			(layer "F.Fab")
			(effects
				(font
					(face "Arial")
					(size 0.63 0.63)
					(thickness 0.1)
				)
				(justify left bottom)
			)
		)
		(pad "1" smd rect
			(at -1.2 -0.95)
			(size 1 0.7)
			(layers "F.Cu" "F.Mask" "F.Paste")
			(net "GND")
			(solder_mask_margin 0)
			(solder_paste_margin 0)
		)
		(pad "2" smd rect
			(at -1.2 0)
			(size 1 0.7)
			(layers "F.Cu" "F.Mask" "F.Paste")
			(net "NetR15_1")
			(solder_mask_margin 0)
			(solder_paste_margin 0)
		)
		(pad "3" smd rect
			(at -1.2 0.95)
			(size 1 0.7)
			(layers "F.Cu" "F.Mask" "F.Paste")
			(net "GND")
			(solder_mask_margin 0)
			(solder_paste_margin 0)
		)
		(pad "4" smd rect
			(at 1.2 0.95)
			(size 1 0.7)
			(layers "F.Cu" "F.Mask" "F.Paste")
			(net "ANT3")
			(solder_mask_margin 0)
			(solder_paste_margin 0)
		)
		(pad "5" smd rect
			(at 1.2 -0.95)
			(size 1 0.7)
			(layers "F.Cu" "F.Mask" "F.Paste")
			(net "+3.3V")
			(solder_mask_margin 0)
			(solder_paste_margin 0)
		)
	)
	(footprint "Vault:FP-318BQ-MFG"
		(layer "F.Cu")
		(at 86.488595 110.5786 180)
		(property "Reference" "U11"
			(at -1.228605 2.723079 0)
			(unlocked yes)
			(layer "F.SilkS")
			(effects
				(font
					(size 0.762 0.762)
					(thickness 0.2286)
				)
			)
		)
		(property "Value" "NC7SZ125M5"
			(at 5.03956 3.495792 180)
			(unlocked yes)
			(layer "F.SilkS")
			(hide yes)
			(effects
				(font
					(size 1.524 1.524)
					(thickness 0.254)
				)
			)
		)
		(sheetname "USER_IO")
		(sheetfile "USER_IO.kicad_sch")
		(duplicate_pad_numbers_are_jumpers no)
		(fp_line
			(start 0.825 -0.225)
			(end 0.825 0.225)
			(stroke
				(width 0.2)
				(type solid)
			)
			(layer "F.SilkS")
		)
		(fp_line
			(start 0.325 1.575)
			(end -0.325 1.575)
			(stroke
				(width 0.2)
				(type solid)
			)
			(layer "F.SilkS")
		)
		(fp_line
			(start 0.325 -1.575)
			(end -0.325 -1.575)
			(stroke
				(width 0.2)
				(type solid)
			)
			(layer "F.SilkS")
		)
		(fp_circle
			(center -2.45 -0.95)
			(end -2.45 -0.825)
			(stroke
				(width 0.25)
				(type solid)
			)
			(fill no)
			(layer "F.SilkS")
		)
		(fp_line
			(start 1.8 1.825)
			(end -1.8 1.825)
			(stroke
				(width 0.2)
				(type solid)
			)
			(layer "F.CrtYd")
		)
		(fp_line
			(start 1.8 -1.825)
			(end 1.8 1.825)
			(stroke
				(width 0.2)
				(type solid)
			)
			(layer "F.CrtYd")
		)
		(fp_line
			(start 1.8 -1.825)
			(end -1.8 -1.825)
			(stroke
				(width 0.2)
				(type solid)
			)
			(layer "F.CrtYd")
		)
		(fp_line
			(start -1.8 -1.825)
			(end -1.8 1.825)
			(stroke
				(width 0.2)
				(type solid)
			)
			(layer "F.CrtYd")
		)
		(fp_line
			(start 1.8 1.825)
			(end -1.8 1.825)
			(stroke
				(width 0.2)
				(type solid)
			)
			(layer "F.Fab")
		)
		(fp_line
			(start 1.8 -1.825)
			(end 1.8 1.825)
			(stroke
				(width 0.2)
				(type solid)
			)
			(layer "F.Fab")
		)
		(fp_line
			(start 1.8 -1.825)
			(end -1.8 -1.825)
			(stroke
				(width 0.2)
				(type solid)
			)
			(layer "F.Fab")
		)
		(fp_line
			(start 0.5 0)
			(end -0.5 0)
			(stroke
				(width 0.1)
				(type solid)
			)
			(layer "F.Fab")
		)
		(fp_line
			(start 0 -0.5)
			(end 0 0.5)
			(stroke
				(width 0.1)
				(type solid)
			)
			(layer "F.Fab")
		)
		(fp_line
			(start -1.8 -1.825)
			(end -1.8 1.825)
			(stroke
				(width 0.2)
				(type solid)
			)
			(layer "F.Fab")
		)
		(fp_text user "${REFERENCE}"
			(at 0 0.28494 180)
			(unlocked yes)
			(layer "F.Fab")
			(effects
				(font
					(face "Arial")
					(size 0.63 0.63)
					(thickness 0.1)
				)
				(justify left bottom)
			)
		)
		(pad "1" smd rect
			(at -1.2 -0.95 180)
			(size 1 0.7)
			(layers "F.Cu" "F.Mask" "F.Paste")
			(net "GND")
			(solder_mask_margin 0)
			(solder_paste_margin 0)
		)
		(pad "2" smd rect
			(at -1.2 0 180)
			(size 1 0.7)
			(layers "F.Cu" "F.Mask" "F.Paste")
			(net "ANT2")
			(solder_mask_margin 0)
			(solder_paste_margin 0)
		)
		(pad "3" smd rect
			(at -1.2 0.95 180)
			(size 1 0.7)
			(layers "F.Cu" "F.Mask" "F.Paste")
			(net "GND")
			(solder_mask_margin 0)
			(solder_paste_margin 0)
		)
		(pad "4" smd rect
			(at 1.2 0.95 180)
			(size 1 0.7)
			(layers "F.Cu" "F.Mask" "F.Paste")
			(net "NetR17_1")
			(solder_mask_margin 0)
			(solder_paste_margin 0)
		)
		(pad "5" smd rect
			(at 1.2 -0.95 180)
			(size 1 0.7)
			(layers "F.Cu" "F.Mask" "F.Paste")
			(net "+3.3V")
			(solder_mask_margin 0)
			(solder_paste_margin 0)
		)
	)
	(footprint "Vault:CAPC1608X87X45ML20T05"
		(layer "F.Cu")
		(at 219.588595 92.6786 180)
		(property "Reference" "C12"
			(at 4.2 0.106655 0)
			(unlocked yes)
			(layer "F.SilkS")
			(effects
				(font
					(size 0.762 0.762)
					(thickness 0.2286)
				)
				(justify left bottom)
			)
		)
		(property "Value" "0.1uF"
			(at -12.7889 -3.09499 0)
			(unlocked yes)
			(layer "F.SilkS")
			(hide yes)
			(effects
				(font
					(size 1.524 1.524)
					(thickness 0.254)
				)
				(justify left bottom)
			)
		)
		(sheetname "POWER")
		(sheetfile "POWER.kicad_sch")
		(duplicate_pad_numbers_are_jumpers no)
		(pad "1" smd rect
			(at -0.7 0 270)
			(size 1.1 1.05)
			(layers "F.Cu" "F.Mask" "F.Paste")
			(net "GND")
		)
		(pad "2" smd rect
			(at 0.7 0 270)
			(size 1.1 1.05)
			(layers "F.Cu" "F.Mask" "F.Paste")
			(net "+3.3V")
		)
	)
	(footprint "Vault:CAPC1608X87X45ML20T05"
		(layer "F.Cu")
		(at 86.488595 100.3286)
		(property "Reference" "C26"
			(at -2.8214 0.026921 0)
			(unlocked yes)
			(layer "F.SilkS")
			(effects
				(font
					(size 0.762 0.762)
					(thickness 0.2286)
				)
			)
		)
		(property "Value" "0.1uF"
			(at 2.09443 2.657602 0)
			(unlocked yes)
			(layer "F.SilkS")
			(hide yes)
			(effects
				(font
					(size 1.524 1.524)
					(thickness 0.254)
				)
			)
		)
		(sheetname "USER_IO")
		(sheetfile "USER_IO.kicad_sch")
		(duplicate_pad_numbers_are_jumpers no)
		(pad "1" smd rect
			(at -0.7 0 90)
			(size 1.1 1.05)
			(layers "F.Cu" "F.Mask" "F.Paste")
			(net "+3.3V")
		)
		(pad "2" smd rect
			(at 0.7 0 90)
			(size 1.1 1.05)
			(layers "F.Cu" "F.Mask" "F.Paste")
			(net "GND")
		)
	)
	(footprint "Vault:RESC1609X50X30NL10T20"
		(layer "F.Cu")
		(at 174.238595 87.5786 -90)
		(property "Reference" "R12"
			(at 2.2714 -0.026931 90)
			(unlocked yes)
			(layer "F.SilkS")
			(effects
				(font
					(size 0.762 0.762)
					(thickness 0.2286)
				)
			)
		)
		(property "Value" "110R"
			(at -2.911592 2.27248 180)
			(unlocked yes)
			(layer "F.SilkS")
			(hide yes)
			(effects
				(font
					(size 1.524 1.524)
					(thickness 0.254)
				)
			)
		)
		(sheetname "MAC")
		(sheetfile "MAC.kicad_sch")
		(duplicate_pad_numbers_are_jumpers no)
		(pad "1" smd rect
			(at -0.625 0)
			(size 0.95 0.8)
			(layers "F.Cu" "F.Mask" "F.Paste")
			(net "MAC_PPS_OUT-")
		)
		(pad "2" smd rect
			(at 0.625 0)
			(size 0.95 0.8)
			(layers "F.Cu" "F.Mask" "F.Paste")
			(net "MAC_PPS_OUT+")
		)
	)
	(footprint "Connectors:AMPHENOL-901-143-6RFX"
		(layer "F.Cu")
		(at 63.564595 110.8946 180)
		(property "Reference" "AN2"
			(at 4.076 -6.277345 0)
			(unlocked yes)
			(layer "F.SilkS")
			(effects
				(font
					(size 0.762 0.762)
					(thickness 0.2286)
				)
				(justify left bottom)
			)
		)
		(property "Value" "901-143-6RFX"
			(at 4.6101 -2.05359 0)
			(unlocked yes)
			(layer "F.SilkS")
			(hide yes)
			(effects
				(font
					(size 1.524 1.524)
					(thickness 0.254)
				)
				(justify left bottom)
			)
		)
		(sheetname "USER_IO")
		(sheetfile "USER_IO.kicad_sch")
		(duplicate_pad_numbers_are_jumpers no)
		(fp_line
			(start 4.318 3.556)
			(end 3.302 4.572)
			(stroke
				(width 0.1778)
				(type solid)
			)
			(layer "F.SilkS")
		)
		(fp_line
			(start 4.318 -3.556)
			(end 3.302 -4.572)
			(stroke
				(width 0.1778)
				(type solid)
			)
			(layer "F.SilkS")
		)
		(fp_line
			(start 3.302 4.572)
			(end 2.54 4.572)
			(stroke
				(width 0.1778)
				(type solid)
			)
			(layer "F.SilkS")
		)
		(fp_line
			(start 3.302 -4.572)
			(end 2.54 -4.572)
			(stroke
				(width 0.1778)
				(type solid)
			)
			(layer "F.SilkS")
		)
		(fp_line
			(start 2.54 4.572)
			(end -4.572 4.572)
			(stroke
				(width 0.1778)
				(type solid)
			)
			(layer "F.SilkS")
		)
		(fp_line
			(start 2.54 -4.572)
			(end -4.572 -4.572)
			(stroke
				(width 0.1778)
				(type solid)
			)
			(layer "F.SilkS")
		)
		(fp_line
			(start -4.572 2.54)
			(end -4.572 4.572)
			(stroke
				(width 0.1778)
				(type solid)
			)
			(layer "F.SilkS")
		)
		(fp_line
			(start -4.572 -4.572)
			(end -4.572 -2.54)
			(stroke
				(width 0.1778)
				(type solid)
			)
			(layer "F.SilkS")
		)
		(pad "1" thru_hole circle
			(at 0 0 180)
			(size 2.8448 2.8448)
			(drill 1.524)
			(layers "*.Cu" "*.Mask")
			(remove_unused_layers no)
			(net "NetAN2_1")
			(thermal_bridge_angle 90)
		)
		(pad "2" thru_hole circle
			(at -2.54 2.54 180)
			(size 3.048 3.048)
			(drill 1.7272)
			(layers "*.Cu" "*.Mask")
			(remove_unused_layers no)
			(net "GND")
			(thermal_bridge_angle 90)
		)
		(pad "3" thru_hole circle
			(at -2.54 -2.54 180)
			(size 3.048 3.048)
			(drill 1.7272)
			(layers "*.Cu" "*.Mask")
			(remove_unused_layers no)
			(net "GND")
			(thermal_bridge_angle 90)
		)
		(pad "4" thru_hole circle
			(at 2.54 -2.54 180)
			(size 3.048 3.048)
			(drill 1.7272)
			(layers "*.Cu" "*.Mask")
			(remove_unused_layers no)
			(net "GND")
			(thermal_bridge_angle 90)
		)
		(pad "5" thru_hole circle
			(at 2.54 2.54 180)
			(size 3.048 3.048)
			(drill 1.7272)
			(layers "*.Cu" "*.Mask")
			(remove_unused_layers no)
			(net "GND")
			(thermal_bridge_angle 90)
		)
	)
	(footprint "Vault:RESC1608X55X30NL15T15"
		(layer "F.Cu")
		(at 74.788595 56.9786 90)
		(property "Reference" "R16"
			(at 0.1286 -1.673069 90)
			(unlocked yes)
			(layer "F.SilkS")
			(effects
				(font
					(size 0.762 0.762)
					(thickness 0.2286)
				)
			)
		)
		(property "Value" "200 OHM"
			(at -2.085402 4.85075 0)
			(unlocked yes)
			(layer "F.SilkS")
			(hide yes)
			(effects
				(font
					(size 1.524 1.524)
					(thickness 0.254)
				)
			)
		)
		(sheetname "USER_IO")
		(sheetfile "USER_IO.kicad_sch")
		(duplicate_pad_numbers_are_jumpers no)
		(pad "1" smd rect
			(at -0.675 0 180)
			(size 0.95 0.8)
			(layers "F.Cu" "F.Mask" "F.Paste")
			(net "LED1")
		)
		(pad "2" smd rect
			(at 0.675 0 180)
			(size 0.95 0.8)
			(layers "F.Cu" "F.Mask" "F.Paste")
			(net "NetD11_1")
		)
	)
	(footprint "Capacitors:CAPC2012X14N"
		(layer "F.Cu")
		(at 219.393595 106.0686 -90)
		(property "Reference" "C5"
			(at 3.41 -0.488345 90)
			(unlocked yes)
			(layer "F.SilkS")
			(effects
				(font
					(size 0.762 0.762)
					(thickness 0.2286)
				)
				(justify left bottom)
			)
		)
		(property "Value" "CAP_0805_10UF_25V"
			(at -19.07921 -10.6045 0)
			(unlocked yes)
			(layer "F.SilkS")
			(hide yes)
			(effects
				(font
					(size 1.524 1.524)
					(thickness 0.254)
				)
				(justify left bottom)
			)
		)
		(sheetname "POWER")
		(sheetfile "POWER.kicad_sch")
		(duplicate_pad_numbers_are_jumpers no)
		(fp_line
			(start 0.762 0.9652)
			(end -0.762 0.9652)
			(stroke
				(width 0.1524)
				(type solid)
			)
			(layer "F.SilkS")
		)
		(fp_line
			(start 0.762 -0.9652)
			(end -0.762 -0.9652)
			(stroke
				(width 0.1524)
				(type solid)
			)
			(layer "F.SilkS")
		)
		(pad "1" smd rect
			(at -0.9 0)
			(size 1.45 1.15)
			(layers "F.Cu" "F.Mask" "F.Paste")
			(net "+12V")
		)
		(pad "2" smd rect
			(at 0.9 0)
			(size 1.45 1.15)
			(layers "F.Cu" "F.Mask" "F.Paste")
			(net "GND")
		)
	)
	(footprint "Vault:TECO-1909763-1_V"
		(layer "F.Cu")
		(at 71.838595 124.1786 90)
		(property "Reference" "J9"
			(at -1.421395 2.926921 90)
			(unlocked yes)
			(layer "F.SilkS")
			(effects
				(font
					(size 0.762 0.762)
					(thickness 0.2286)
				)
			)
		)
		(property "Value" "1909763-1"
			(at 4.608085 3.749802 90)
			(unlocked yes)
			(layer "F.SilkS")
			(hide yes)
			(effects
				(font
					(size 1.524 1.524)
					(thickness 0.254)
				)
			)
		)
		(sheetname "USER_IO")
		(sheetfile "USER_IO.kicad_sch")
		(duplicate_pad_numbers_are_jumpers no)
		(fp_line
			(start -0.55 -1.3)
			(end 0.55 -1.3)
			(stroke
				(width 0.2)
				(type solid)
			)
			(layer "F.SilkS")
		)
		(fp_circle
			(center -1.778 1.65)
			(end -1.653 1.65)
			(stroke
				(width 0.25)
				(type solid)
			)
			(fill no)
			(layer "F.SilkS")
		)
		(pad "1" smd rect
			(at -1.475 0 90)
			(size 1.05 2.2)
			(layers "F.Cu" "F.Mask" "F.Paste")
			(net "GND")
		)
		(pad "2" smd rect
			(at 0 1.525 90)
			(size 1 1.05)
			(layers "F.Cu" "F.Mask" "F.Paste")
			(net "NetAN3_1")
		)
		(pad "3" smd rect
			(at 1.475 0 90)
			(size 1.05 2.2)
			(layers "F.Cu" "F.Mask" "F.Paste")
			(net "GND")
		)
	)
	(footprint "Vault:M08A_L"
		(layer "F.Cu")
		(at 178.988595 88.8286)
		(property "Reference" "U4"
			(at 1.478605 -3.473069 0)
			(unlocked yes)
			(layer "F.SilkS")
			(effects
				(font
					(size 0.762 0.762)
					(thickness 0.2286)
				)
			)
		)
		(property "Value" "DS90LV028AQMA"
			(at 6.74058 4.207002 0)
			(unlocked yes)
			(layer "F.SilkS")
			(hide yes)
			(effects
				(font
					(size 1.524 1.524)
					(thickness 0.254)
				)
			)
		)
		(sheetname "MAC")
		(sheetfile "MAC.kicad_sch")
		(duplicate_pad_numbers_are_jumpers no)
		(fp_line
			(start -1 -2.5)
			(end 1 -2.5)
			(stroke
				(width 0.2)
				(type solid)
			)
			(layer "F.SilkS")
		)
		(fp_line
			(start -1 2.5)
			(end -1 -2.5)
			(stroke
				(width 0.2)
				(type solid)
			)
			(layer "F.SilkS")
		)
		(fp_line
			(start -1 2.5)
			(end 1 2.5)
			(stroke
				(width 0.2)
				(type solid)
			)
			(layer "F.SilkS")
		)
		(fp_line
			(start 1 2.5)
			(end 1 -2.5)
			(stroke
				(width 0.2)
				(type solid)
			)
			(layer "F.SilkS")
		)
		(fp_circle
			(center -2.35 -2.755)
			(end -2.35 -2.88)
			(stroke
				(width 0.25)
				(type solid)
			)
			(fill no)
			(layer "F.SilkS")
		)
		(fp_circle
			(center -0.2 -1.7)
			(end -0.2 -1.9)
			(stroke
				(width 0.4)
				(type solid)
			)
			(fill no)
			(layer "F.SilkS")
		)
		(pad "1" smd oval
			(at -2.35 -1.905 90)
			(size 0.6 1.9)
			(layers "F.Cu" "F.Mask" "F.Paste")
			(net "MAC_PPS_OUT-")
		)
		(pad "2" smd oval
			(at -2.35 -0.635 90)
			(size 0.6 1.9)
			(layers "F.Cu" "F.Mask" "F.Paste")
			(net "MAC_PPS_OUT+")
		)
		(pad "3" smd oval
			(at -2.35 0.635 90)
			(size 0.6 1.9)
			(layers "F.Cu" "F.Mask" "F.Paste")
		)
		(pad "4" smd oval
			(at -2.35 1.905 90)
			(size 0.6 1.9)
			(layers "F.Cu" "F.Mask" "F.Paste")
		)
		(pad "5" smd oval
			(at 2.35 1.905 90)
			(size 0.6 1.9)
			(layers "F.Cu" "F.Mask" "F.Paste")
			(net "GND")
		)
		(pad "6" smd oval
			(at 2.35 0.635 90)
			(size 0.6 1.9)
			(layers "F.Cu" "F.Mask" "F.Paste")
		)
		(pad "7" smd oval
			(at 2.35 -0.635 90)
			(size 0.6 1.9)
			(layers "F.Cu" "F.Mask" "F.Paste")
			(net "NetR13_1")
		)
		(pad "8" smd oval
			(at 2.35 -1.905 90)
			(size 0.6 1.9)
			(layers "F.Cu" "F.Mask" "F.Paste")
			(net "+3.3V")
		)
	)
)
